# BASEBOARD_FAB2 (Tioga Pass) — schematic netlist excerpt (pin names and nets, part order shuffled) for the footprints in the layout excerpt that follows; sources: Cadence DE-HDL packaged netlist, KiCad conversion of Wiwynn_Tioga_Pass_MB.brd

R32W1  RES  4.02K 1% CHIP  pkg 0402  page 185 : A = P3V3 ; B = P1V8_M2
R2U44  RES  221 1.0% CHIP  pkg 0402  page 161 : A = FAN_PWM_OUT_SYS1_BUF ; B = FAN_PWM_OUT_SYS1_R
R1L28  RES  4.75K 1% EMPTY  pkg 0402  page 111 : A = P3V3_STBY ; B = FM_DEBUG_RST_BTN_R1_N

(kicad_pcb
	(version 20260206)
	(generator "pcbnew")
	(generator_version "10.0")
	(general
		(thickness 1.6)
		(legacy_teardrops no)
	)
	(paper "A4")
	(title_block
		(title "Wiwynn_Tioga_Pass_MB.brd")
		(comment 1 "Tioga Pass / footprints 3191-3193 of 4770")
	)
	(layers
		(0 "F.Cu" signal "TOP")
		(4 "In1.Cu" signal "L2GND")
		(6 "In2.Cu" signal "L3")
		(8 "In3.Cu" signal "L4GND")
		(10 "In4.Cu" signal "L5")
		(12 "In5.Cu" signal "L6GND")
		(14 "In6.Cu" signal "L7VCC")
		(16 "In7.Cu" signal "L8VCC")
		(18 "In8.Cu" signal "L9GND")
		(20 "In9.Cu" signal "L10")
		(22 "In10.Cu" signal "L11GND")
		(24 "In11.Cu" signal "L12")
		(26 "In12.Cu" signal "L13GND")
		(2 "B.Cu" signal "BOTTOM")
		(9 "F.Adhes" user "F.Adhesive")
		(11 "B.Adhes" user "B.Adhesive")
		(13 "F.Paste" user "Package Geometry/Pastemask Top")
		(15 "B.Paste" user "Package Geometry/Pastemask Bottom")
		(5 "F.SilkS" user "Ref Des/Silkscreen Top")
		(7 "B.SilkS" user "Ref Des/Silkscreen Bottom")
		(1 "F.Mask" user "Board Geometry/Soldermask Top")
		(3 "B.Mask" user "Board Geometry/Soldermask Bottom")
		(17 "Dwgs.User" user "User.Drawings")
		(19 "Cmts.User" user "User.Comments")
		(21 "Eco1.User" user "User.Eco1")
		(23 "Eco2.User" user "User.Eco2")
		(25 "Edge.Cuts" user "Board Geometry/Outline")
		(27 "Margin" user)
		(31 "F.CrtYd" user "Package Geometry/Place Bound Top")
		(29 "B.CrtYd" user "Package Geometry/Place Bound Bottom")
		(35 "F.Fab" user "Ref Des/Assembly Top")
		(33 "B.Fab" user "Ref Des/Assembly Bottom")
	)
	(footprint ""
		(layer "B.Cu")
		(at 393.446 -18.9103 180)
		(property "Reference" "R32W1"
			(at 0.8382 -0.67818 180)
			(unlocked yes)
			(layer "B.SilkS")
			(effects
				(font
					(size 0.4064 0.254)
					(thickness 0.1524)
				)
				(justify left mirror)
			)
		)
		(property "Value" ""
			(at 0 0 0)
			(layer "B.Fab")
			(effects
				(font
					(size 1.27 1.27)
				)
				(justify mirror)
			)
		)
		(duplicate_pad_numbers_are_jumpers no)
		(fp_poly
			(pts
				(xy 0.2794 -0.1016) (xy -0.2794 -0.1016) (xy -0.2794 0.9906) (xy 0.2794 0.9906)
			)
			(stroke
				(width 0)
				(type default)
			)
			(fill no)
			(layer "B.CrtYd")
		)
		(fp_line
			(start 0.2794 0.9906)
			(end -0.2794 0.9906)
			(stroke
				(width 0.1)
				(type default)
			)
			(layer "B.Fab")
		)
		(fp_line
			(start 0.2794 -0.1016)
			(end 0.2794 0.9906)
			(stroke
				(width 0.1)
				(type default)
			)
			(layer "B.Fab")
		)
		(fp_line
			(start -0.2794 0.9906)
			(end -0.2794 -0.1016)
			(stroke
				(width 0.1)
				(type default)
			)
			(layer "B.Fab")
		)
		(fp_line
			(start -0.2794 -0.1016)
			(end 0.2794 -0.1016)
			(stroke
				(width 0.1)
				(type default)
			)
			(layer "B.Fab")
		)
		(pad "1" smd rect
			(at 0 0)
			(size 0.508 0.508)
			(layers "B.Cu" "B.Mask" "B.Paste")
			(net "P3V3")
		)
		(pad "2" smd rect
			(at 0 0.889)
			(size 0.508 0.508)
			(layers "B.Cu" "B.Mask" "B.Paste")
			(net "P1V8_M2")
		)
		(zone
			(layer "B.Cu")
			(hatch none 0.5)
			(connect_pads
				(clearance 0)
			)
			(min_thickness 0.25)
			(keepout
				(tracks not_allowed)
				(vias allowed)
				(pads allowed)
				(copperpour not_allowed)
				(footprints allowed)
			)
			(placement
				(enabled no)
				(sheetname "")
			)
			(fill
				(thermal_gap 0.5)
				(thermal_bridge_width 0.5)
				(island_removal_mode 0)
			)
			(polygon
				(pts
					(xy 393.192 -19.5453) (xy 393.7 -19.5453) (xy 393.7 -19.1643) (xy 393.192 -19.1643)
				)
			)
		)
		(zone
			(layer "B.Cu")
			(hatch none 0.5)
			(connect_pads
				(clearance 0)
			)
			(min_thickness 0.25)
			(keepout
				(tracks allowed)
				(vias not_allowed)
				(pads allowed)
				(copperpour not_allowed)
				(footprints allowed)
			)
			(placement
				(enabled no)
				(sheetname "")
			)
			(fill
				(thermal_gap 0.5)
				(thermal_bridge_width 0.5)
				(island_removal_mode 0)
			)
			(polygon
				(pts
					(xy 393.192 -19.1643) (xy 393.7 -19.1643) (xy 393.7 -19.5453) (xy 393.192 -19.5453)
				)
			)
		)
	)
	(footprint ""
		(layer "B.Cu")
		(at 457.8096 -142.9004)
		(property "Reference" "R1L28"
			(at 0 0 0)
			(layer "B.SilkS")
			(hide yes)
			(effects
				(font
					(size 1.27 1.27)
				)
				(justify mirror)
			)
		)
		(property "Value" ""
			(at 0 0 0)
			(layer "B.Fab")
			(effects
				(font
					(size 1.27 1.27)
				)
				(justify mirror)
			)
		)
		(duplicate_pad_numbers_are_jumpers no)
		(fp_poly
			(pts
				(xy 0.2794 -0.1016) (xy -0.2794 -0.1016) (xy -0.2794 0.9906) (xy 0.2794 0.9906)
			)
			(stroke
				(width 0)
				(type default)
			)
			(fill no)
			(layer "B.CrtYd")
		)
		(fp_line
			(start -0.2794 -0.1016)
			(end 0.2794 -0.1016)
			(stroke
				(width 0.1)
				(type default)
			)
			(layer "B.Fab")
		)
		(fp_line
			(start -0.2794 0.9906)
			(end -0.2794 -0.1016)
			(stroke
				(width 0.1)
				(type default)
			)
			(layer "B.Fab")
		)
		(fp_line
			(start 0.2794 -0.1016)
			(end 0.2794 0.9906)
			(stroke
				(width 0.1)
				(type default)
			)
			(layer "B.Fab")
		)
		(fp_line
			(start 0.2794 0.9906)
			(end -0.2794 0.9906)
			(stroke
				(width 0.1)
				(type default)
			)
			(layer "B.Fab")
		)
		(pad "1" smd rect
			(at 0 0 180)
			(size 0.508 0.508)
			(layers "B.Cu" "B.Mask" "B.Paste")
			(net "P3V3_STBY")
		)
		(pad "2" smd rect
			(at 0 0.889 180)
			(size 0.508 0.508)
			(layers "B.Cu" "B.Mask" "B.Paste")
			(net "FM_DEBUG_RST_BTN_R1_N")
		)
		(zone
			(layer "B.Cu")
			(hatch none 0.5)
			(connect_pads
				(clearance 0)
			)
			(min_thickness 0.25)
			(keepout
				(tracks allowed)
				(vias not_allowed)
				(pads allowed)
				(copperpour not_allowed)
				(footprints allowed)
			)
			(placement
				(enabled no)
				(sheetname "")
			)
			(fill
				(thermal_gap 0.5)
				(thermal_bridge_width 0.5)
				(island_removal_mode 0)
			)
			(polygon
				(pts
					(xy 458.0636 -142.6464) (xy 457.5556 -142.6464) (xy 457.5556 -142.2654) (xy 458.0636 -142.2654)
				)
			)
		)
		(zone
			(layer "B.Cu")
			(hatch none 0.5)
			(connect_pads
				(clearance 0)
			)
			(min_thickness 0.25)
			(keepout
				(tracks not_allowed)
				(vias allowed)
				(pads allowed)
				(copperpour not_allowed)
				(footprints allowed)
			)
			(placement
				(enabled no)
				(sheetname "")
			)
			(fill
				(thermal_gap 0.5)
				(thermal_bridge_width 0.5)
				(island_removal_mode 0)
			)
			(polygon
				(pts
					(xy 458.0636 -142.2654) (xy 457.5556 -142.2654) (xy 457.5556 -142.6464) (xy 458.0636 -142.6464)
				)
			)
		)
	)
	(footprint ""
		(layer "B.Cu")
		(at 403.8854 3.3782 -90)
		(property "Reference" "R2U44"
			(at 0 0 90)
			(layer "B.SilkS")
			(hide yes)
			(effects
				(font
					(size 1.27 1.27)
				)
				(justify mirror)
			)
		)
		(property "Value" ""
			(at 0 0 90)
			(layer "B.Fab")
			(effects
				(font
					(size 1.27 1.27)
				)
				(justify mirror)
			)
		)
		(duplicate_pad_numbers_are_jumpers no)
		(fp_poly
			(pts
				(xy 0.2794 -0.1016) (xy -0.2794 -0.1016) (xy -0.2794 0.9906) (xy 0.2794 0.9906)
			)
			(stroke
				(width 0)
				(type default)
			)
			(fill no)
			(layer "B.CrtYd")
		)
		(fp_line
			(start -0.2794 0.9906)
			(end -0.2794 -0.1016)
			(stroke
				(width 0.1)
				(type default)
			)
			(layer "B.Fab")
		)
		(fp_line
			(start 0.2794 0.9906)
			(end -0.2794 0.9906)
			(stroke
				(width 0.1)
				(type default)
			)
			(layer "B.Fab")
		)
		(fp_line
			(start -0.2794 -0.1016)
			(end 0.2794 -0.1016)
			(stroke
				(width 0.1)
				(type default)
			)
			(layer "B.Fab")
		)
		(fp_line
			(start 0.2794 -0.1016)
			(end 0.2794 0.9906)
			(stroke
				(width 0.1)
				(type default)
			)
			(layer "B.Fab")
		)
		(pad "1" smd rect
			(at 0 0 90)
			(size 0.508 0.508)
			(layers "B.Cu" "B.Mask" "B.Paste")
			(net "FAN_PWM_OUT_SYS1_BUF")
		)
		(pad "2" smd rect
			(at 0 0.889 90)
			(size 0.508 0.508)
			(layers "B.Cu" "B.Mask" "B.Paste")
			(net "FAN_PWM_OUT_SYS1_R")
		)
		(zone
			(layer "B.Cu")
			(hatch none 0.5)
			(connect_pads
				(clearance 0)
			)
			(min_thickness 0.25)
			(keepout
				(tracks not_allowed)
				(vias allowed)
				(pads allowed)
				(copperpour not_allowed)
				(footprints allowed)
			)
			(placement
				(enabled no)
				(sheetname "")
			)
			(fill
				(thermal_gap 0.5)
				(thermal_bridge_width 0.5)
				(island_removal_mode 0)
			)
			(polygon
				(pts
					(xy 403.2504 3.6322) (xy 403.2504 3.1242) (xy 403.6314 3.1242) (xy 403.6314 3.6322)
				)
			)
		)
		(zone
			(layer "B.Cu")
			(hatch none 0.5)
			(connect_pads
				(clearance 0)
			)
			(min_thickness 0.25)
			(keepout
				(tracks allowed)
				(vias not_allowed)
				(pads allowed)
				(copperpour not_allowed)
				(footprints allowed)
			)
			(placement
				(enabled no)
				(sheetname "")
			)
			(fill
				(thermal_gap 0.5)
				(thermal_bridge_width 0.5)
				(island_removal_mode 0)
			)
			(polygon
				(pts
					(xy 403.6314 3.6322) (xy 403.6314 3.1242) (xy 403.2504 3.1242) (xy 403.2504 3.6322)
				)
			)
		)
	)
)
